# S9S_MB_2U (Grand Teton) — schematic netlist excerpt (pin names and nets, part order shuffled) for the footprints in the layout excerpt that follows; sources: Cadence DE-HDL packaged netlist, KiCad conversion of 03242023_DA0F0TMBIJ0_F0T_Motherboard_J_brd_V01_OCP.brd

J30  SCONN288_ADR50017P087CC  SCONN288_ADR50017-P087CC IO  pkg DDR288S_1-1VXB  page 111
  VIN_BULK0  = P12V_S3_AUX_CPU1_NVDIMM
  RFU0  = TP_CHG_CPU1_DIMM2_FRU_0
  VIN_MGMT  = P3V3_AUX
  HSCL  = I3C_SPD_DDREFGH_CPU1_LVC1_SCL_5
  HSDA  = I3C_SPD_DDREFGH_CPU1_LVC1_SDA
  VSS0  = GND
  DQ0_A  = M_G_CPU1_SA_DQ<0>
  VSS1  = GND
  DQ1_A  = M_G_CPU1_SA_DQ<1>
  VSS2  = GND
  DQS0_A_T  = M_G_CPU1_SA_DQS_DP<0>
  DQS0_A_C  = M_G_CPU1_SA_DQS_DN<0>
  VSS3  = GND
  DQ4_A  = M_G_CPU1_SA_DQ<4>
  VSS4  = GND
  DQ5_A  = M_G_CPU1_SA_DQ<5>
  VSS5  = GND
  DQ8_A  = M_G_CPU1_SA_DQ<8>
  VSS6  = GND
  DQ9_A  = M_G_CPU1_SA_DQ<9>
  VSS7  = GND
  DQS1_A_T  = M_G_CPU1_SA_DQS_DP<1>
  DQS1_A_C  = M_G_CPU1_SA_DQS_DN<1>
  VSS8  = GND
  DQ12_A  = M_G_CPU1_SA_DQ<12>
  VSS9  = GND
  DQ13_A  = M_G_CPU1_SA_DQ<13>
  VSS10  = GND
  DQ16_A  = M_G_CPU1_SA_DQ<16>
  VSS11  = GND
  DQ17_A  = M_G_CPU1_SA_DQ<17>
  VSS12  = GND
  DQS2_A_T  = M_G_CPU1_SA_DQS_DP<2>
  DQS2_A_C  = M_G_CPU1_SA_DQS_DN<2>
  VSS13  = GND
  DQ20_A  = M_G_CPU1_SA_DQ<20>
  VSS14  = GND
  DQ21_A  = M_G_CPU1_SA_DQ<21>
  VSS15  = GND
  DQ24_A  = M_G_CPU1_SA_DQ<24>
  VSS16  = GND
  DQ25_A  = M_G_CPU1_SA_DQ<25>
  VSS17  = GND
  DQS3_A_T  = M_G_CPU1_SA_DQS_DP<3>
  DQS3_A_C  = M_G_CPU1_SA_DQS_DN<3>
  VSS18  = GND
  DQ28_A  = M_G_CPU1_SA_DQ<28>
  VSS19  = GND
  DQ29_A  = M_G_CPU1_SA_DQ<29>
  VSS20  = GND
  CB0_A  = M_G_CPU1_SA_CB<0>
  VSS21  = GND
  CB1_A  = M_G_CPU1_SA_CB<1>
  VSS22  = GND
  DQS4_A_T  = M_G_CPU1_SA_DQS_DP<4>
  DQS4_A_C  = M_G_CPU1_SA_DQS_DN<4>
  VSS23  = GND
  CB4_A  = M_G_CPU1_SA_CB<4>
  VSS24  = GND
  CB5_A  = M_G_CPU1_SA_CB<5>
  VSS25  = GND
  ALERT_N  = M_G_CPU1_ALERT_N
  VSS26  = GND
  CS0_A_N  = M_G_CPU1_SA_CS_N<2>
  VSS27  = GND
  CA0_A  = M_G_CPU1_SA_CA<0>
  VSS28  = GND
  CA2_A  = M_G_CPU1_SA_CA<2>
  VSS29  = GND
  CA4_A  = M_G_CPU1_SA_CA<4>
  VSS30  = GND
  CA6_A  = M_G_CPU1_SA_CA<6>
  VSS31  = GND
  PAR_A  = M_G_CPU1_SA_PAR
  VSS32  = GND
  CA0_B  = M_G_CPU1_SB_CA<0>
  VSS33  = GND
  CA2_B  = M_G_CPU1_SB_CA<2>
  VSS34  = GND
  CA4_B  = M_G_CPU1_SB_CA<4>
  VSS35  = GND
  CA6_B  = M_G_CPU1_SB_CA<6>
  VSS36  = GND
  CS0_B_N  = M_G_CPU1_SB_CS_N<2>
  VSS37  = GND
  \lbd||rsp_a_n\  = M_G_CPU1_SA_RSP<1>
  \lbs||rsp_b_n\  = M_G_CPU1_SB_RSP<1>
  VSS38  = GND
  CB4_B  = M_G_CPU1_SB_CB<4>
  VSS39  = GND
  CB5_B  = M_G_CPU1_SB_CB<5>
  VSS40  = GND
  \dqs9_b_t||tdqs9_b_t||dbi4_b_n\  = M_G_CPU1_SB_DQS_DP<9>
  \dqs9_b_c||tdqs9_b_c\  = M_G_CPU1_SB_DQS_DN<9>
  VSS41  = GND
  CB0_B  = M_G_CPU1_SB_CB<0>
  VSS42  = GND
  CB1_B  = M_G_CPU1_SB_CB<1>
  VSS43  = GND
  DQ0_B  = M_G_CPU1_SB_DQ<0>
  VSS44  = GND
  DQ1_B  = M_G_CPU1_SB_DQ<1>
  VSS45  = GND
  DQS0_B_T  = M_G_CPU1_SB_DQS_DP<0>
  DQS0_B_C  = M_G_CPU1_SB_DQS_DN<0>
  VSS46  = GND
  DQ4_B  = M_G_CPU1_SB_DQ<4>
  VSS47  = GND
  DQ5_B  = M_G_CPU1_SB_DQ<5>
  VSS48  = GND
  DQ8_B  = M_G_CPU1_SB_DQ<8>
  VSS49  = GND
  DQ9_B  = M_G_CPU1_SB_DQ<9>
  VSS50  = GND
  DQS1_B_T  = M_G_CPU1_SB_DQS_DP<1>
  DQS1_B_C  = M_G_CPU1_SB_DQS_DN<1>
  VSS51  = GND
  DQ12_B  = M_G_CPU1_SB_DQ<12>
  VSS52  = GND
  DQ13_B  = M_G_CPU1_SB_DQ<13>
  VSS53  = GND
  DQ16_B  = M_G_CPU1_SB_DQ<16>
  VSS54  = GND
  DQ17_B  = M_G_CPU1_SB_DQ<17>
  VSS55  = GND
  DQS2_B_T  = M_G_CPU1_SB_DQS_DP<2>
  DQS2_B_C  = M_G_CPU1_SB_DQS_DN<2>
  VSS56  = GND
  DQ20_B  = M_G_CPU1_SB_DQ<20>
  VSS57  = GND
  DQ21_B  = M_G_CPU1_SB_DQ<21>
  VSS58  = GND
  DQ24_B  = M_G_CPU1_SB_DQ<24>
  VSS59  = GND
  DQ25_B  = M_G_CPU1_SB_DQ<25>
  VSS60  = GND
  DQS3_B_T  = M_G_CPU1_SB_DQS_DP<3>
  DQS3_B_C  = M_G_CPU1_SB_DQS_DN<3>
  VSS61  = GND
  DQ28_B  = M_G_CPU1_SB_DQ<28>
  VSS62  = GND
  DQ29_B  = M_G_CPU1_SB_DQ<29>
  VSS63  = GND
  RFU1  = TP_CHG_CPU1_DIMM2_FRU_1
  VIN_BULK1  = P12V_S3_AUX_CPU1_NVDIMM
  VIN_BULK2  = P12V_S3_AUX_CPU1_NVDIMM
  \pwr_good||fail_n\  = PWRGD_CHG_CPU1_DIMM2
  HSA  = PD_CHG_CPU1_DIMM2_SAA
  RFU2  = TP_CHG_CPU1_DIMM2_FRU_2
  RFU3  = TP_CHG_CPU1_DIMM2_FRU_3
  VSS64  = GND
  DQ2_A  = M_G_CPU1_SA_DQ<2>
  VSS65  = GND
  DQ3_A  = M_G_CPU1_SA_DQ<3>
  VSS66  = GND
  \dqs5_a_c||tdqs5_a_c||dqs5_a_t||tdqs5_a_t\  = M_G_CPU1_SA_DQS_DN<5>
  \dqs5_a_t||tdqs5_a_t\  = M_G_CPU1_SA_DQS_DP<5>
  VSS67  = GND
  DQ6_A  = M_G_CPU1_SA_DQ<6>
  VSS68  = GND
  DQ7_A  = M_G_CPU1_SA_DQ<7>
  VSS69  = GND
  DQ10_A  = M_G_CPU1_SA_DQ<10>
  VSS70  = GND
  DQ11_A  = M_G_CPU1_SA_DQ<11>
  VSS71  = GND
  \dqs6_a_c||tdqs6_a_c||dqs6_a_t||tdqs6_a_t\  = M_G_CPU1_SA_DQS_DN<6>
  \dqs6_a_t||tdqs6_a_t\  = M_G_CPU1_SA_DQS_DP<6>
  VSS72  = GND
  DQ14_A  = M_G_CPU1_SA_DQ<14>
  VSS73  = GND
  DQ15_A  = M_G_CPU1_SA_DQ<15>
  VSS74  = GND
  DQ18_A  = M_G_CPU1_SA_DQ<18>
  VSS75  = GND
  DQ19_A  = M_G_CPU1_SA_DQ<19>
  VSS76  = GND
  \dqs7_a_c||tdqs7_a_c\  = M_G_CPU1_SA_DQS_DN<7>
  \dqs7_a_t||tdqs7_a_t\  = M_G_CPU1_SA_DQS_DP<7>
  VSS77  = GND
  DQ22_A  = M_G_CPU1_SA_DQ<22>
  VSS78  = GND
  DQ23_A  = M_G_CPU1_SA_DQ<23>
  VSS79  = GND
  DQ26_A  = M_G_CPU1_SA_DQ<26>
  VSS80  = GND
  DQ27_A  = M_G_CPU1_SA_DQ<27>
  VSS81  = GND
  \dqs8_a_c||tdqs8_a_c\  = M_G_CPU1_SA_DQS_DN<8>
  \dqs8_a_t||tdqs8_a_t\  = M_G_CPU1_SA_DQS_DP<8>
  VSS82  = GND
  DQ30_A  = M_G_CPU1_SA_DQ<30>
  VSS83  = GND
  DQ31_A  = M_G_CPU1_SA_DQ<31>
  VSS84  = GND
  CB2_A  = M_G_CPU1_SA_CB<2>
  VSS85  = GND
  CB3_A  = M_G_CPU1_SA_CB<3>
  VSS86  = GND
  \dqs9_a_c||tdqs9_a_c\  = M_G_CPU1_SA_DQS_DN<9>
  \dqs9_a_t||tdqs9_a_t\  = M_G_CPU1_SA_DQS_DP<9>
  VSS87  = GND
  CB6_A  = M_G_CPU1_SA_CB<6>
  VSS88  = GND
  CB7_A  = M_G_CPU1_SA_CB<7>
  VSS89  = GND
  RESET_N  = RST_M_GH_CPU1_FPGA_N
  VSS90  = GND
  CS1_A_N  = M_G_CPU1_SA_CS_N<3>
  VSS91  = GND
  CA1_A  = M_G_CPU1_SA_CA<1>
  VSS92  = GND
  CA3_A  = M_G_CPU1_SA_CA<3>
  VSS93  = GND
  CA5_A  = M_G_CPU1_SA_CA<5>
  VSS94  = GND
  CK_T  = M_G_CPU1_CLK_DP<1>
  CK_C  = M_G_CPU1_CLK_DN<1>
  VSS95  = GND
  RFU4  = TP_CHG_CPU1_DIMM2_FRU_4
  CA1_B  = M_G_CPU1_SB_CA<1>
  VSS96  = GND
  CA3_B  = M_G_CPU1_SB_CA<3>
  VSS97  = GND
  CA5_B  = M_G_CPU1_SB_CA<5>
  VSS98  = GND
  PAR_B  = M_G_CPU1_SB_PAR
  VSS99  = GND
  CS1_B_N  = M_G_CPU1_SB_CS_N<3>
  VSS100  = GND
  RFU5  = TP_CHG_CPU1_DIMM2_FRU_5
  RFU6  = TP_CHG_CPU1_DIMM2_FRU_6
  VSS101  = GND
  CB6_B  = M_G_CPU1_SB_CB<6>
  VSS102  = GND
  CB7_B  = M_G_CPU1_SB_CB<7>
  VSS103  = GND
  DQS4_B_C  = M_G_CPU1_SB_DQS_DN<4>
  DQS4_B_T  = M_G_CPU1_SB_DQS_DP<4>
  VSS104  = GND
  CB2_B  = M_G_CPU1_SB_CB<2>
  VSS105  = GND
  CB3_B  = M_G_CPU1_SB_CB<3>
  VSS106  = GND
  DQ2_B  = M_G_CPU1_SB_DQ<2>
  VSS107  = GND
  DQ3_B  = M_G_CPU1_SB_DQ<3>
  VSS108  = GND
  \dqs5_b_c||tdqs5_b_c\  = M_G_CPU1_SB_DQS_DN<5>
  \dqs5_b_t||tdqs5_b_t\  = M_G_CPU1_SB_DQS_DP<5>
  VSS109  = GND
  DQ6_B  = M_G_CPU1_SB_DQ<6>
  VSS110  = GND
  DQ7_B  = M_G_CPU1_SB_DQ<7>
  VSS111  = GND
  DQ10_B  = M_G_CPU1_SB_DQ<10>
  VSS112  = GND
  DQ11_B  = M_G_CPU1_SB_DQ<11>
  VSS113  = GND
  \dqs6_b_c||tdqs6_b_c\  = M_G_CPU1_SB_DQS_DN<6>
  \dqs6_b_t||tdqs6_b_t\  = M_G_CPU1_SB_DQS_DP<6>
  VSS114  = GND
  DQ14_B  = M_G_CPU1_SB_DQ<14>
  VSS115  = GND
  DQ15_B  = M_G_CPU1_SB_DQ<15>
  VSS116  = GND
  DQ18_B  = M_G_CPU1_SB_DQ<18>
  VSS117  = GND
  DQ19_B  = M_G_CPU1_SB_DQ<19>
  VSS118  = GND
  \dqs7_b_c||tdqs7_b_c\  = M_G_CPU1_SB_DQS_DN<7>
  \dqs7_b_t||tdqs7_b_t\  = M_G_CPU1_SB_DQS_DP<7>
  VSS119  = GND
  DQ22_B  = M_G_CPU1_SB_DQ<22>
  VSS120  = GND
  DQ23_B  = M_G_CPU1_SB_DQ<23>
  VSS121  = GND
  DQ26_B  = M_G_CPU1_SB_DQ<26>
  VSS122  = GND
  DQ27_B  = M_G_CPU1_SB_DQ<27>
  VSS123  = GND
  \dqs8_b_c||tdqs8_b_c\  = M_G_CPU1_SB_DQS_DN<8>
  \dqs8_b_t||tdqs8_b_t\  = M_G_CPU1_SB_DQS_DP<8>
  VSS124  = GND
  DQ30_B  = M_G_CPU1_SB_DQ<30>
  VSS125  = GND
  DQ31_B  = M_G_CPU1_SB_DQ<31>
  VSS126  = GND
  G1  = GND
  G2  = GND
  G3  = GND

(kicad_pcb
	(version 20260206)
	(generator "pcbnew")
	(generator_version "10.0")
	(general
		(thickness 1.6)
		(legacy_teardrops no)
	)
	(paper "A4")
	(title_block
		(title "03242023_DA0F0TMBIJ0_F0T_Motherboard_J_brd_V01_OCP.brd")
		(comment 1 "Grand Teton / footprint 1354 of 6105 (J30), pads 183-228 of 291")
	)
	(layers
		(0 "F.Cu" signal "TOP")
		(4 "In1.Cu" signal "GND")
		(6 "In2.Cu" signal "IN1")
		(8 "In3.Cu" signal "GND1")
		(10 "In4.Cu" signal "IN2")
		(12 "In5.Cu" signal "GND2")
		(14 "In6.Cu" signal "IN3")
		(16 "In7.Cu" signal "GND3")
		(18 "In8.Cu" signal "VCC")
		(20 "In9.Cu" signal "VCC1")
		(22 "In10.Cu" signal "GND4")
		(24 "In11.Cu" signal "IN4")
		(26 "In12.Cu" signal "GND5")
		(28 "In13.Cu" signal "IN5")
		(30 "In14.Cu" signal "GND6")
		(32 "In15.Cu" signal "IN6")
		(34 "In16.Cu" signal "GND7")
		(2 "B.Cu" signal "BOTTOM")
		(9 "F.Adhes" user "F.Adhesive")
		(11 "B.Adhes" user "B.Adhesive")
		(13 "F.Paste" user "Package Geometry/Pastemask Top")
		(15 "B.Paste" user "Package Geometry/Pastemask Bottom")
		(5 "F.SilkS" user "Ref Des/Silkscreen Top")
		(7 "B.SilkS" user "Ref Des/Silkscreen Bottom")
		(1 "F.Mask" user "Board Geometry/Soldermask Top")
		(3 "B.Mask" user "Board Geometry/Soldermask Bottom")
		(17 "Dwgs.User" user "User.Drawings")
		(19 "Cmts.User" user "User.Comments")
		(21 "Eco1.User" user "User.Eco1")
		(23 "Eco2.User" user "User.Eco2")
		(25 "Edge.Cuts" user "Board Geometry/Outline")
		(27 "Margin" user)
		(31 "F.CrtYd" user "Package Geometry/Place Bound Top")
		(29 "B.CrtYd" user "Package Geometry/Place Bound Bottom")
		(35 "F.Fab" user "Ref Des/Assembly Top")
		(33 "B.Fab" user "Ref Des/Assembly Bottom")
	)
	(footprint ""
		(layer "F.Cu")
		(at 191.03848 -258.091686)
		(property "Reference" "J30"
			(at -2.98196 -81.740248 0)
			(unlocked yes)
			(layer "F.SilkS")
			(effects
				(font
					(size 0.7874 0.5842)
					(thickness 0.1524)
				)
				(justify left)
			)
		)
		(property "Value" ""
			(at 0 0 0)
			(layer "F.Fab")
			(effects
				(font
					(size 1.27 1.27)
				)
			)
		)
		(duplicate_pad_numbers_are_jumpers no)
		(pad "183" smd rect
			(at 2.050034 -31.025084 270)
			(size 0.519938 1.4986)
			(layers "F.Cu" "F.Mask" "F.Paste")
			(net "M_G_CPU1_SA_DQ<23>")
		)
		(pad "184" smd rect
			(at 2.050034 -30.174946 270)
			(size 0.519938 1.4986)
			(layers "F.Cu" "F.Mask" "F.Paste")
			(net "GND")
		)
		(pad "185" smd rect
			(at 2.050034 -29.325062 270)
			(size 0.519938 1.4986)
			(layers "F.Cu" "F.Mask" "F.Paste")
			(net "M_G_CPU1_SA_DQ<26>")
		)
		(pad "186" smd rect
			(at 2.050034 -28.474924 270)
			(size 0.519938 1.4986)
			(layers "F.Cu" "F.Mask" "F.Paste")
			(net "GND")
		)
		(pad "187" smd rect
			(at 2.050034 -27.62504 270)
			(size 0.519938 1.4986)
			(layers "F.Cu" "F.Mask" "F.Paste")
			(net "M_G_CPU1_SA_DQ<27>")
		)
		(pad "188" smd rect
			(at 2.050034 -26.774902 270)
			(size 0.519938 1.4986)
			(layers "F.Cu" "F.Mask" "F.Paste")
			(net "GND")
		)
		(pad "189" smd rect
			(at 2.050034 -25.925018 270)
			(size 0.519938 1.4986)
			(layers "F.Cu" "F.Mask" "F.Paste")
			(net "M_G_CPU1_SA_DQS_DN<8>")
		)
		(pad "190" smd rect
			(at 2.050034 -25.07488 270)
			(size 0.519938 1.4986)
			(layers "F.Cu" "F.Mask" "F.Paste")
			(net "M_G_CPU1_SA_DQS_DP<8>")
		)
		(pad "191" smd rect
			(at 2.050034 -24.224996 270)
			(size 0.519938 1.4986)
			(layers "F.Cu" "F.Mask" "F.Paste")
			(net "GND")
		)
		(pad "192" smd rect
			(at 2.050034 -23.375112 270)
			(size 0.519938 1.4986)
			(layers "F.Cu" "F.Mask" "F.Paste")
			(net "M_G_CPU1_SA_DQ<30>")
		)
		(pad "193" smd rect
			(at 2.050034 -22.524974 270)
			(size 0.519938 1.4986)
			(layers "F.Cu" "F.Mask" "F.Paste")
			(net "GND")
		)
		(pad "194" smd rect
			(at 2.050034 -21.67509 270)
			(size 0.519938 1.4986)
			(layers "F.Cu" "F.Mask" "F.Paste")
			(net "M_G_CPU1_SA_DQ<31>")
		)
		(pad "195" smd rect
			(at 2.050034 -20.824952 270)
			(size 0.519938 1.4986)
			(layers "F.Cu" "F.Mask" "F.Paste")
			(net "GND")
		)
		(pad "196" smd rect
			(at 2.050034 -19.975068 270)
			(size 0.519938 1.4986)
			(layers "F.Cu" "F.Mask" "F.Paste")
			(net "M_G_CPU1_SA_CB<2>")
		)
		(pad "197" smd rect
			(at 2.050034 -19.12493 270)
			(size 0.519938 1.4986)
			(layers "F.Cu" "F.Mask" "F.Paste")
			(net "GND")
		)
		(pad "198" smd rect
			(at 2.050034 -18.275046 270)
			(size 0.519938 1.4986)
			(layers "F.Cu" "F.Mask" "F.Paste")
			(net "M_G_CPU1_SA_CB<3>")
		)
		(pad "199" smd rect
			(at 2.050034 -17.424908 270)
			(size 0.519938 1.4986)
			(layers "F.Cu" "F.Mask" "F.Paste")
			(net "GND")
		)
		(pad "200" smd rect
			(at 2.050034 -16.575024 270)
			(size 0.519938 1.4986)
			(layers "F.Cu" "F.Mask" "F.Paste")
			(net "M_G_CPU1_SA_DQS_DN<9>")
		)
		(pad "201" smd rect
			(at 2.050034 -15.724886 270)
			(size 0.519938 1.4986)
			(layers "F.Cu" "F.Mask" "F.Paste")
			(net "M_G_CPU1_SA_DQS_DP<9>")
		)
		(pad "202" smd rect
			(at 2.050034 -14.875002 270)
			(size 0.519938 1.4986)
			(layers "F.Cu" "F.Mask" "F.Paste")
			(net "GND")
		)
		(pad "203" smd rect
			(at 2.050034 -14.025118 270)
			(size 0.519938 1.4986)
			(layers "F.Cu" "F.Mask" "F.Paste")
			(net "M_G_CPU1_SA_CB<6>")
		)
		(pad "204" smd rect
			(at 2.050034 -13.17498 270)
			(size 0.519938 1.4986)
			(layers "F.Cu" "F.Mask" "F.Paste")
			(net "GND")
		)
		(pad "205" smd rect
			(at 2.050034 -12.325096 270)
			(size 0.519938 1.4986)
			(layers "F.Cu" "F.Mask" "F.Paste")
			(net "M_G_CPU1_SA_CB<7>")
		)
		(pad "206" smd rect
			(at 2.050034 -11.474958 270)
			(size 0.519938 1.4986)
			(layers "F.Cu" "F.Mask" "F.Paste")
			(net "GND")
		)
		(pad "207" smd rect
			(at 2.050034 -10.625074 270)
			(size 0.519938 1.4986)
			(layers "F.Cu" "F.Mask" "F.Paste")
			(net "RST_M_GH_CPU1_FPGA_N")
		)
		(pad "208" smd rect
			(at 2.050034 -9.774936 270)
			(size 0.519938 1.4986)
			(layers "F.Cu" "F.Mask" "F.Paste")
			(net "GND")
		)
		(pad "209" smd rect
			(at 2.050034 -8.925052 270)
			(size 0.519938 1.4986)
			(layers "F.Cu" "F.Mask" "F.Paste")
			(net "M_G_CPU1_SA_CS_N<3>")
		)
		(pad "210" smd rect
			(at 2.050034 -8.074914 270)
			(size 0.519938 1.4986)
			(layers "F.Cu" "F.Mask" "F.Paste")
			(net "GND")
		)
		(pad "211" smd rect
			(at 2.050034 -7.22503 270)
			(size 0.519938 1.4986)
			(layers "F.Cu" "F.Mask" "F.Paste")
			(net "M_G_CPU1_SA_CA<1>")
		)
		(pad "212" smd rect
			(at 2.050034 -6.374892 270)
			(size 0.519938 1.4986)
			(layers "F.Cu" "F.Mask" "F.Paste")
			(net "GND")
		)
		(pad "213" smd rect
			(at 2.050034 -5.525008 270)
			(size 0.519938 1.4986)
			(layers "F.Cu" "F.Mask" "F.Paste")
			(net "M_G_CPU1_SA_CA<3>")
		)
		(pad "214" smd rect
			(at 2.050034 -4.675124 270)
			(size 0.519938 1.4986)
			(layers "F.Cu" "F.Mask" "F.Paste")
			(net "GND")
		)
		(pad "215" smd rect
			(at 2.050034 -3.824986 270)
			(size 0.519938 1.4986)
			(layers "F.Cu" "F.Mask" "F.Paste")
			(net "M_G_CPU1_SA_CA<5>")
		)
		(pad "216" smd rect
			(at 2.050034 -2.975102 270)
			(size 0.519938 1.4986)
			(layers "F.Cu" "F.Mask" "F.Paste")
			(net "GND")
		)
		(pad "217" smd rect
			(at 2.050034 -2.124964 270)
			(size 0.519938 1.4986)
			(layers "F.Cu" "F.Mask" "F.Paste")
			(net "M_G_CPU1_CLK_DP<1>")
		)
		(pad "218" smd rect
			(at 2.050034 -1.27508 270)
			(size 0.519938 1.4986)
			(layers "F.Cu" "F.Mask" "F.Paste")
			(net "M_G_CPU1_CLK_DN<1>")
		)
		(pad "219" smd rect
			(at 2.050034 -0.424942 270)
			(size 0.519938 1.4986)
			(layers "F.Cu" "F.Mask" "F.Paste")
			(net "GND")
		)
		(pad "220" smd rect
			(at 2.050034 5.525008 270)
			(size 0.519938 1.4986)
			(layers "F.Cu" "F.Mask" "F.Paste")
			(net "TP_CHG_CPU1_DIMM2_FRU_4")
		)
		(pad "221" smd rect
			(at 2.050034 6.374892 270)
			(size 0.519938 1.4986)
			(layers "F.Cu" "F.Mask" "F.Paste")
			(net "M_G_CPU1_SB_CA<1>")
		)
		(pad "222" smd rect
			(at 2.050034 7.22503 270)
			(size 0.519938 1.4986)
			(layers "F.Cu" "F.Mask" "F.Paste")
			(net "GND")
		)
		(pad "223" smd rect
			(at 2.050034 8.074914 270)
			(size 0.519938 1.4986)
			(layers "F.Cu" "F.Mask" "F.Paste")
			(net "M_G_CPU1_SB_CA<3>")
		)
		(pad "224" smd rect
			(at 2.050034 8.925052 270)
			(size 0.519938 1.4986)
			(layers "F.Cu" "F.Mask" "F.Paste")
			(net "GND")
		)
		(pad "225" smd rect
			(at 2.050034 9.774936 270)
			(size 0.519938 1.4986)
			(layers "F.Cu" "F.Mask" "F.Paste")
			(net "M_G_CPU1_SB_CA<5>")
		)
		(pad "226" smd rect
			(at 2.050034 10.625074 270)
			(size 0.519938 1.4986)
			(layers "F.Cu" "F.Mask" "F.Paste")
			(net "GND")
		)
		(pad "227" smd rect
			(at 2.050034 11.474958 270)
			(size 0.519938 1.4986)
			(layers "F.Cu" "F.Mask" "F.Paste")
			(net "M_G_CPU1_SB_PAR")
		)
		(pad "228" smd rect
			(at 2.050034 12.325096 270)
			(size 0.519938 1.4986)
			(layers "F.Cu" "F.Mask" "F.Paste")
			(net "GND")
		)
	)
)
